(kicad_pcb
	(version 20241229)
	(generator "pcbnew")
	(generator_version "9.0")
	(general
		(thickness 1.62)
		(legacy_teardrops no)
	)
	(paper "A3")
	(title_block
		(title "COM Express 7 Baseboard")
		(date "2025-02-04")
		(rev "1.1.2")
		(company "Antmicro Ltd")
		(comment 1 "www.antmicro.com")
		(comment 9 "footprint 323 of 802 (J100), pads 1-41 of 71")
	)
	(layers
		(0 "F.Cu" signal)
		(4 "In1.Cu" signal)
		(6 "In2.Cu" signal)
		(8 "In3.Cu" signal)
		(10 "In4.Cu" signal)
		(12 "In5.Cu" signal)
		(14 "In6.Cu" signal)
		(2 "B.Cu" signal)
		(9 "F.Adhes" user "F.Adhesive")
		(11 "B.Adhes" user "B.Adhesive")
		(13 "F.Paste" user)
		(15 "B.Paste" user)
		(5 "F.SilkS" user "F.Silkscreen")
		(7 "B.SilkS" user "B.Silkscreen")
		(1 "F.Mask" user)
		(3 "B.Mask" user)
		(17 "Dwgs.User" user "User.Drawings")
		(19 "Cmts.User" user "User.Comments")
		(21 "Eco1.User" user "User.Eco1")
		(23 "Eco2.User" user "User.Eco2")
		(25 "Edge.Cuts" user)
		(27 "Margin" user)
		(31 "F.CrtYd" user "F.Courtyard")
		(29 "B.CrtYd" user "B.Courtyard")
		(35 "F.Fab" user)
		(33 "B.Fab" user)
	)
	(footprint "antmicro-footprints:Bus_M.2_Socket_Key_E_TE_2199230-6"
		(layer "F.Cu")
		(at 149.8245 80.3095 -90)
		(property "Reference" "J100"
			(at 12.2505 2.0245 180)
			(layer "F.SilkS")
			(effects
				(font
					(size 0.7 0.7)
					(thickness 0.15)
				)
				(justify right bottom)
			)
		)
		(property "Value" "Bus_M.2_2199230-2"
			(at -10.999 5.75 90)
			(layer "F.Fab")
			(effects
				(font
					(size 0.7 0.7)
					(thickness 0.15)
				)
				(justify right bottom)
			)
		)
		(property "Datasheet" "https://eu.mouser.com/datasheet/2/418/9/ENG_DS_1_1773702_1NGFFQRG_EN_0214_1_1773702_1NGFF_-3328593.pdf"
			(at 0 0 270)
			(layer "F.Fab")
			(hide yes)
			(effects
				(font
					(size 1.27 1.27)
					(thickness 0.15)
				)
			)
		)
		(property "Author" "Antmicro"
			(at 69.515 230.134 0)
			(layer "F.Fab")
			(hide yes)
			(effects
				(font
					(size 1 1)
					(thickness 0.15)
				)
			)
		)
		(property "License" "Apache-2.0"
			(at 69.515 230.134 0)
			(layer "F.Fab")
			(hide yes)
			(effects
				(font
					(size 1 1)
					(thickness 0.15)
				)
			)
		)
		(property "MPN" "2199230-2"
			(at 69.515 230.134 0)
			(layer "F.Fab")
			(hide yes)
			(effects
				(font
					(size 1 1)
					(thickness 0.15)
				)
			)
		)
		(property "Manufacturer" "TE Connectivity"
			(at 69.515 230.134 0)
			(layer "F.Fab")
			(hide yes)
			(effects
				(font
					(size 1 1)
					(thickness 0.15)
				)
			)
		)
		(sheetname "M.2 key E")
		(sheetfile "m2keye.kicad_sch")
		(attr smd)
		(pad "" np_thru_hole circle
			(at -9.999 1.499 270)
			(size 1.1 1.1)
			(drill 1.1)
			(layers "*.Cu" "*.Mask")
		)
		(pad "" np_thru_hole circle
			(at 9.999 1.499 270)
			(size 1.6 1.6)
			(drill 1.6)
			(layers "*.Cu" "*.Mask")
		)
		(pad "1" smd rect
			(at -9.249 -3.749 270)
			(size 0.3 1.55)
			(layers "F.Cu" "F.Mask" "F.Paste")
			(net 1 "GND")
			(pinfunction "GND")
			(pintype "power_in")
			(teardrops
				(best_length_ratio 0.2)
				(max_length 1)
				(best_width_ratio 0.9)
				(max_width 2)
				(curved_edges yes)
				(filter_ratio 0.9)
				(enabled yes)
				(allow_two_segments yes)
				(prefer_zone_connections yes)
			)
		)
		(pad "2" smd rect
			(at -9.001 3.749 270)
			(size 0.3 1.55)
			(layers "F.Cu" "F.Mask" "F.Paste")
			(net 2 "+3V3")
			(pinfunction "3.3V")
			(pintype "power_in")
			(teardrops
				(best_length_ratio 0.2)
				(max_length 1)
				(best_width_ratio 0.9)
				(max_width 2)
				(curved_edges yes)
				(filter_ratio 0.9)
				(enabled yes)
				(allow_two_segments yes)
				(prefer_zone_connections yes)
			)
		)
		(pad "3" smd rect
			(at -8.751 -3.749 270)
			(size 0.3 1.55)
			(layers "F.Cu" "F.Mask" "F.Paste")
			(net 3 "/M.2 key E/WIFI_BT_USB_D_P")
			(pinfunction "USB_D_P")
			(pintype "bidirectional")
			(teardrops
				(best_length_ratio 0.2)
				(max_length 1)
				(best_width_ratio 0.9)
				(max_width 2)
				(curved_edges yes)
				(filter_ratio 0.9)
				(enabled yes)
				(allow_two_segments yes)
				(prefer_zone_connections yes)
			)
		)
		(pad "4" smd rect
			(at -8.501 3.749 270)
			(size 0.3 1.55)
			(layers "F.Cu" "F.Mask" "F.Paste")
			(net 2 "+3V3")
			(pinfunction "3.3V")
			(pintype "passive")
			(teardrops
				(best_length_ratio 0.2)
				(max_length 1)
				(best_width_ratio 0.9)
				(max_width 2)
				(curved_edges yes)
				(filter_ratio 0.9)
				(enabled yes)
				(allow_two_segments yes)
				(prefer_zone_connections yes)
			)
		)
		(pad "5" smd rect
			(at -8.251 -3.749 270)
			(size 0.3 1.55)
			(layers "F.Cu" "F.Mask" "F.Paste")
			(net 4 "/M.2 key E/WIFI_BT_USB_D_N")
			(pinfunction "USB_D_N")
			(pintype "bidirectional")
			(teardrops
				(best_length_ratio 0.2)
				(max_length 1)
				(best_width_ratio 0.9)
				(max_width 2)
				(curved_edges yes)
				(filter_ratio 0.9)
				(enabled yes)
				(allow_two_segments yes)
				(prefer_zone_connections yes)
			)
		)
		(pad "6" smd rect
			(at -8 3.749 270)
			(size 0.3 1.55)
			(layers "F.Cu" "F.Mask" "F.Paste")
			(net 5 "/M.2 key E/~{LED_1}")
			(pinfunction "~{LED_1}")
			(pintype "output")
			(teardrops
				(best_length_ratio 0.2)
				(max_length 1)
				(best_width_ratio 0.9)
				(max_width 2)
				(curved_edges yes)
				(filter_ratio 0.9)
				(enabled yes)
				(allow_two_segments yes)
				(prefer_zone_connections yes)
			)
		)
		(pad "7" smd rect
			(at -7.75 -3.749 270)
			(size 0.3 1.55)
			(layers "F.Cu" "F.Mask" "F.Paste")
			(net 1 "GND")
			(pinfunction "GND")
			(pintype "passive")
			(teardrops
				(best_length_ratio 0.2)
				(max_length 1)
				(best_width_ratio 0.9)
				(max_width 2)
				(curved_edges yes)
				(filter_ratio 0.9)
				(enabled yes)
				(allow_two_segments yes)
				(prefer_zone_connections yes)
			)
		)
		(pad "8" smd rect
			(at -7.5 3.749 270)
			(size 0.3 1.55)
			(layers "F.Cu" "F.Mask" "F.Paste")
			(net 7 "unconnected-(J100-PCM_CLK-Pad8)")
			(pinfunction "PCM_CLK")
			(pintype "bidirectional+no_connect")
			(teardrops
				(best_length_ratio 0.2)
				(max_length 1)
				(best_width_ratio 0.9)
				(max_width 2)
				(curved_edges yes)
				(filter_ratio 0.9)
				(enabled yes)
				(allow_two_segments yes)
				(prefer_zone_connections yes)
			)
		)
		(pad "9" smd rect
			(at -7.25 -3.749 270)
			(size 0.3 1.55)
			(layers "F.Cu" "F.Mask" "F.Paste")
			(net 8 "unconnected-(J100-SDIO_CLK-Pad9)")
			(pinfunction "SDIO_CLK")
			(pintype "input+no_connect")
			(teardrops
				(best_length_ratio 0.2)
				(max_length 1)
				(best_width_ratio 0.9)
				(max_width 2)
				(curved_edges yes)
				(filter_ratio 0.9)
				(enabled yes)
				(allow_two_segments yes)
				(prefer_zone_connections yes)
			)
		)
		(pad "10" smd rect
			(at -7 3.749 270)
			(size 0.3 1.55)
			(layers "F.Cu" "F.Mask" "F.Paste")
			(net 10 "unconnected-(J100-PCM_SYNC-Pad10)")
			(pinfunction "PCM_SYNC")
			(pintype "bidirectional+no_connect")
			(teardrops
				(best_length_ratio 0.2)
				(max_length 1)
				(best_width_ratio 0.9)
				(max_width 2)
				(curved_edges yes)
				(filter_ratio 0.9)
				(enabled yes)
				(allow_two_segments yes)
				(prefer_zone_connections yes)
			)
		)
		(pad "11" smd rect
			(at -6.75 -3.749 270)
			(size 0.3 1.55)
			(layers "F.Cu" "F.Mask" "F.Paste")
			(net 12 "unconnected-(J100-SDIO_CMD-Pad11)")
			(pinfunction "SDIO_CMD")
			(pintype "bidirectional+no_connect")
			(teardrops
				(best_length_ratio 0.2)
				(max_length 1)
				(best_width_ratio 0.9)
				(max_width 2)
				(curved_edges yes)
				(filter_ratio 0.9)
				(enabled yes)
				(allow_two_segments yes)
				(prefer_zone_connections yes)
			)
		)
		(pad "12" smd rect
			(at -6.5 3.749 270)
			(size 0.3 1.55)
			(layers "F.Cu" "F.Mask" "F.Paste")
			(net 13 "unconnected-(J100-PCM_IN-Pad12)")
			(pinfunction "PCM_IN")
			(pintype "bidirectional+no_connect")
			(teardrops
				(best_length_ratio 0.2)
				(max_length 1)
				(best_width_ratio 0.9)
				(max_width 2)
				(curved_edges yes)
				(filter_ratio 0.9)
				(enabled yes)
				(allow_two_segments yes)
				(prefer_zone_connections yes)
			)
		)
		(pad "13" smd rect
			(at -6.25 -3.749 270)
			(size 0.3 1.55)
			(layers "F.Cu" "F.Mask" "F.Paste")
			(net 15 "unconnected-(J100-SDIO_D0-Pad13)")
			(pinfunction "SDIO_D0")
			(pintype "bidirectional+no_connect")
			(teardrops
				(best_length_ratio 0.2)
				(max_length 1)
				(best_width_ratio 0.9)
				(max_width 2)
				(curved_edges yes)
				(filter_ratio 0.9)
				(enabled yes)
				(allow_two_segments yes)
				(prefer_zone_connections yes)
			)
		)
		(pad "14" smd rect
			(at -6 3.749 270)
			(size 0.3 1.55)
			(layers "F.Cu" "F.Mask" "F.Paste")
			(net 17 "unconnected-(J100-PCM_OUT-Pad14)")
			(pinfunction "PCM_OUT")
			(pintype "bidirectional+no_connect")
			(teardrops
				(best_length_ratio 0.2)
				(max_length 1)
				(best_width_ratio 0.9)
				(max_width 2)
				(curved_edges yes)
				(filter_ratio 0.9)
				(enabled yes)
				(allow_two_segments yes)
				(prefer_zone_connections yes)
			)
		)
		(pad "15" smd rect
			(at -5.75 -3.749 270)
			(size 0.3 1.55)
			(layers "F.Cu" "F.Mask" "F.Paste")
			(net 18 "unconnected-(J100-SDIO_D1-Pad15)")
			(pinfunction "SDIO_D1")
			(pintype "bidirectional+no_connect")
			(teardrops
				(best_length_ratio 0.2)
				(max_length 1)
				(best_width_ratio 0.9)
				(max_width 2)
				(curved_edges yes)
				(filter_ratio 0.9)
				(enabled yes)
				(allow_two_segments yes)
				(prefer_zone_connections yes)
			)
		)
		(pad "16" smd rect
			(at -5.5 3.749 270)
			(size 0.3 1.55)
			(layers "F.Cu" "F.Mask" "F.Paste")
			(net 6 "/M.2 key E/~{LED_2}")
			(pinfunction "~{LED_2}")
			(pintype "output")
			(teardrops
				(best_length_ratio 0.2)
				(max_length 1)
				(best_width_ratio 0.9)
				(max_width 2)
				(curved_edges yes)
				(filter_ratio 0.9)
				(enabled yes)
				(allow_two_segments yes)
				(prefer_zone_connections yes)
			)
		)
		(pad "17" smd rect
			(at -5.25 -3.749 270)
			(size 0.3 1.55)
			(layers "F.Cu" "F.Mask" "F.Paste")
			(net 20 "unconnected-(J100-SDIO_D2-Pad17)")
			(pinfunction "SDIO_D2")
			(pintype "bidirectional+no_connect")
			(teardrops
				(best_length_ratio 0.2)
				(max_length 1)
				(best_width_ratio 0.9)
				(max_width 2)
				(curved_edges yes)
				(filter_ratio 0.9)
				(enabled yes)
				(allow_two_segments yes)
				(prefer_zone_connections yes)
			)
		)
		(pad "18" smd rect
			(at -5.001 3.749 270)
			(size 0.3 1.55)
			(layers "F.Cu" "F.Mask" "F.Paste")
			(net 1 "GND")
			(pinfunction "GND")
			(pintype "passive")
			(teardrops
				(best_length_ratio 0.2)
				(max_length 1)
				(best_width_ratio 0.9)
				(max_width 2)
				(curved_edges yes)
				(filter_ratio 0.9)
				(enabled yes)
				(allow_two_segments yes)
				(prefer_zone_connections yes)
			)
		)
		(pad "19" smd rect
			(at -4.751 -3.749 270)
			(size 0.3 1.55)
			(layers "F.Cu" "F.Mask" "F.Paste")
			(net 22 "unconnected-(J100-SDIO_D3-Pad19)")
			(pinfunction "SDIO_D3")
			(pintype "bidirectional+no_connect")
			(teardrops
				(best_length_ratio 0.2)
				(max_length 1)
				(best_width_ratio 0.9)
				(max_width 2)
				(curved_edges yes)
				(filter_ratio 0.9)
				(enabled yes)
				(allow_two_segments yes)
				(prefer_zone_connections yes)
			)
		)
		(pad "20" smd rect
			(at -4.501 3.749 270)
			(size 0.3 1.55)
			(layers "F.Cu" "F.Mask" "F.Paste")
			(net 25 "unconnected-(J100-~{UART_WAKE}-Pad20)")
			(pinfunction "~{UART_WAKE}")
			(pintype "output+no_connect")
			(teardrops
				(best_length_ratio 0.2)
				(max_length 1)
				(best_width_ratio 0.9)
				(max_width 2)
				(curved_edges yes)
				(filter_ratio 0.9)
				(enabled yes)
				(allow_two_segments yes)
				(prefer_zone_connections yes)
			)
		)
		(pad "21" smd rect
			(at -4.251 -3.749 270)
			(size 0.3 1.55)
			(layers "F.Cu" "F.Mask" "F.Paste")
			(net 26 "unconnected-(J100-SDIO_~{WAKE}-Pad21)")
			(pinfunction "SDIO_~{WAKE}")
			(pintype "bidirectional+no_connect")
			(teardrops
				(best_length_ratio 0.2)
				(max_length 1)
				(best_width_ratio 0.9)
				(max_width 2)
				(curved_edges yes)
				(filter_ratio 0.9)
				(enabled yes)
				(allow_two_segments yes)
				(prefer_zone_connections yes)
			)
		)
		(pad "22" smd rect
			(at -4.001 3.749 270)
			(size 0.3 1.55)
			(layers "F.Cu" "F.Mask" "F.Paste")
			(net 27 "unconnected-(J100-UART_RXD-Pad22)")
			(pinfunction "UART_RXD")
			(pintype "bidirectional+no_connect")
			(teardrops
				(best_length_ratio 0.2)
				(max_length 1)
				(best_width_ratio 0.9)
				(max_width 2)
				(curved_edges yes)
				(filter_ratio 0.9)
				(enabled yes)
				(allow_two_segments yes)
				(prefer_zone_connections yes)
			)
		)
		(pad "23" smd rect
			(at -3.75 -3.749 270)
			(size 0.3 1.55)
			(layers "F.Cu" "F.Mask" "F.Paste")
			(net 28 "unconnected-(J100-SDIO_~{RESET}-Pad23)")
			(pinfunction "SDIO_~{RESET}")
			(pintype "input+no_connect")
			(teardrops
				(best_length_ratio 0.2)
				(max_length 1)
				(best_width_ratio 0.9)
				(max_width 2)
				(curved_edges yes)
				(filter_ratio 0.9)
				(enabled yes)
				(allow_two_segments yes)
				(prefer_zone_connections yes)
			)
		)
		(pad "32" smd rect
			(at -1.5 3.749 270)
			(size 0.3 1.55)
			(layers "F.Cu" "F.Mask" "F.Paste")
			(net 29 "unconnected-(J100-UART_TXD-Pad32)")
			(pinfunction "UART_TXD")
			(pintype "bidirectional+no_connect")
			(teardrops
				(best_length_ratio 0.2)
				(max_length 1)
				(best_width_ratio 0.9)
				(max_width 2)
				(curved_edges yes)
				(filter_ratio 0.9)
				(enabled yes)
				(allow_two_segments yes)
				(prefer_zone_connections yes)
			)
		)
		(pad "33" smd rect
			(at -1.25 -3.749 270)
			(size 0.3 1.55)
			(layers "F.Cu" "F.Mask" "F.Paste")
			(net 1 "GND")
			(pinfunction "GND")
			(pintype "passive")
			(teardrops
				(best_length_ratio 0.2)
				(max_length 1)
				(best_width_ratio 0.9)
				(max_width 2)
				(curved_edges yes)
				(filter_ratio 0.9)
				(enabled yes)
				(allow_two_segments yes)
				(prefer_zone_connections yes)
			)
		)
		(pad "34" smd rect
			(at -1 3.749 270)
			(size 0.3 1.55)
			(layers "F.Cu" "F.Mask" "F.Paste")
			(net 30 "unconnected-(J100-UART_CTS-Pad34)")
			(pinfunction "UART_CTS")
			(pintype "bidirectional+no_connect")
			(teardrops
				(best_length_ratio 0.2)
				(max_length 1)
				(best_width_ratio 0.9)
				(max_width 2)
				(curved_edges yes)
				(filter_ratio 0.9)
				(enabled yes)
				(allow_two_segments yes)
				(prefer_zone_connections yes)
			)
		)
		(pad "35" smd rect
			(at -0.75 -3.749 270)
			(size 0.3 1.55)
			(layers "F.Cu" "F.Mask" "F.Paste")
			(net 11 "/Com Express 7 Interfaces/PCIe_{B1x2}.TX0-")
			(pinfunction "PET0_P")
			(pintype "input")
			(teardrops
				(best_length_ratio 0.2)
				(max_length 1)
				(best_width_ratio 0.9)
				(max_width 2)
				(curved_edges yes)
				(filter_ratio 0.9)
				(enabled yes)
				(allow_two_segments yes)
				(prefer_zone_connections yes)
			)
		)
		(pad "36" smd rect
			(at -0.5 3.749 270)
			(size 0.3 1.55)
			(layers "F.Cu" "F.Mask" "F.Paste")
			(net 31 "unconnected-(J100-UART_RTS-Pad36)")
			(pinfunction "UART_RTS")
			(pintype "bidirectional+no_connect")
			(teardrops
				(best_length_ratio 0.2)
				(max_length 1)
				(best_width_ratio 0.9)
				(max_width 2)
				(curved_edges yes)
				(filter_ratio 0.9)
				(enabled yes)
				(allow_two_segments yes)
				(prefer_zone_connections yes)
			)
		)
		(pad "37" smd rect
			(at -0.25 -3.749 270)
			(size 0.3 1.55)
			(layers "F.Cu" "F.Mask" "F.Paste")
			(net 9 "/Com Express 7 Interfaces/PCIe_{B1x2}.TX0+")
			(pinfunction "PET0_N")
			(pintype "input")
			(teardrops
				(best_length_ratio 0.2)
				(max_length 1)
				(best_width_ratio 0.9)
				(max_width 2)
				(curved_edges yes)
				(filter_ratio 0.9)
				(enabled yes)
				(allow_two_segments yes)
				(prefer_zone_connections yes)
			)
		)
		(pad "38" smd rect
			(at 0 3.749 270)
			(size 0.3 1.55)
			(layers "F.Cu" "F.Mask" "F.Paste")
			(net 32 "unconnected-(J100-VENDOR_1-Pad38)")
			(pinfunction "VENDOR_1")
			(pintype "bidirectional+no_connect")
			(teardrops
				(best_length_ratio 0.2)
				(max_length 1)
				(best_width_ratio 0.9)
				(max_width 2)
				(curved_edges yes)
				(filter_ratio 0.9)
				(enabled yes)
				(allow_two_segments yes)
				(prefer_zone_connections yes)
			)
		)
		(pad "39" smd rect
			(at 0.25 -3.749 270)
			(size 0.3 1.55)
			(layers "F.Cu" "F.Mask" "F.Paste")
			(net 1 "GND")
			(pinfunction "GND")
			(pintype "passive")
			(teardrops
				(best_length_ratio 0.2)
				(max_length 1)
				(best_width_ratio 0.9)
				(max_width 2)
				(curved_edges yes)
				(filter_ratio 0.9)
				(enabled yes)
				(allow_two_segments yes)
				(prefer_zone_connections yes)
			)
		)
		(pad "40" smd rect
			(at 0.5 3.749 270)
			(size 0.3 1.55)
			(layers "F.Cu" "F.Mask" "F.Paste")
			(net 33 "unconnected-(J100-VENDOR_2-Pad40)")
			(pinfunction "VENDOR_2")
			(pintype "bidirectional+no_connect")
			(teardrops
				(best_length_ratio 0.2)
				(max_length 1)
				(best_width_ratio 0.9)
				(max_width 2)
				(curved_edges yes)
				(filter_ratio 0.9)
				(enabled yes)
				(allow_two_segments yes)
				(prefer_zone_connections yes)
			)
		)
		(pad "41" smd rect
			(at 0.75 -3.749 270)
			(size 0.3 1.55)
			(layers "F.Cu" "F.Mask" "F.Paste")
			(net 16 "/Com Express 7 Interfaces/PCIe_{B1x2}.RX0-")
			(pinfunction "PER0_P")
			(pintype "output")
			(teardrops
				(best_length_ratio 0.2)
				(max_length 1)
				(best_width_ratio 0.9)
				(max_width 2)
				(curved_edges yes)
				(filter_ratio 0.9)
				(enabled yes)
				(allow_two_segments yes)
				(prefer_zone_connections yes)
			)
		)
		(pad "42" smd rect
			(at 1 3.749 270)
			(size 0.3 1.55)
			(layers "F.Cu" "F.Mask" "F.Paste")
			(net 34 "unconnected-(J100-VENDOR_3-Pad42)")
			(pinfunction "VENDOR_3")
			(pintype "bidirectional+no_connect")
			(teardrops
				(best_length_ratio 0.2)
				(max_length 1)
				(best_width_ratio 0.9)
				(max_width 2)
				(curved_edges yes)
				(filter_ratio 0.9)
				(enabled yes)
				(allow_two_segments yes)
				(prefer_zone_connections yes)
			)
		)
		(pad "43" smd rect
			(at 1.25 -3.749 270)
			(size 0.3 1.55)
			(layers "F.Cu" "F.Mask" "F.Paste")
			(net 14 "/Com Express 7 Interfaces/PCIe_{B1x2}.RX0+")
			(pinfunction "PER0_N")
			(pintype "output")
			(teardrops
				(best_length_ratio 0.2)
				(max_length 1)
				(best_width_ratio 0.9)
				(max_width 2)
				(curved_edges yes)
				(filter_ratio 0.9)
				(enabled yes)
				(allow_two_segments yes)
				(prefer_zone_connections yes)
			)
		)
		(pad "44" smd rect
			(at 1.5 3.749 270)
			(size 0.3 1.55)
			(layers "F.Cu" "F.Mask" "F.Paste")
			(net 35 "unconnected-(J100-COEX3-Pad44)")
			(pinfunction "COEX3")
			(pintype "bidirectional+no_connect")
			(teardrops
				(best_length_ratio 0.2)
				(max_length 1)
				(best_width_ratio 0.9)
				(max_width 2)
				(curved_edges yes)
				(filter_ratio 0.9)
				(enabled yes)
				(allow_two_segments yes)
				(prefer_zone_connections yes)
			)
		)
		(pad "45" smd rect
			(at 1.75 -3.749 270)
			(size 0.3 1.55)
			(layers "F.Cu" "F.Mask" "F.Paste")
			(net 1 "GND")
			(pinfunction "GND")
			(pintype "passive")
			(teardrops
				(best_length_ratio 0.2)
				(max_length 1)
				(best_width_ratio 0.9)
				(max_width 2)
				(curved_edges yes)
				(filter_ratio 0.9)
				(enabled yes)
				(allow_two_segments yes)
				(prefer_zone_connections yes)
			)
		)
		(pad "46" smd rect
			(at 2 3.749 270)
			(size 0.3 1.55)
			(layers "F.Cu" "F.Mask" "F.Paste")
			(net 36 "unconnected-(J100-COEX_TXD-Pad46)")
			(pinfunction "COEX_TXD")
			(pintype "bidirectional+no_connect")
			(teardrops
				(best_length_ratio 0.2)
				(max_length 1)
				(best_width_ratio 0.9)
				(max_width 2)
				(curved_edges yes)
				(filter_ratio 0.9)
				(enabled yes)
				(allow_two_segments yes)
				(prefer_zone_connections yes)
			)
		)
		(pad "47" smd rect
			(at 2.25 -3.749 270)
			(size 0.3 1.55)
			(layers "F.Cu" "F.Mask" "F.Paste")
			(net 21 "/M.2 key E/PCIE_{REF}.CK-")
			(pinfunction "REFCLK0_P")
			(pintype "input")
			(teardrops
				(best_length_ratio 0.2)
				(max_length 1)
				(best_width_ratio 0.9)
				(max_width 2)
				(curved_edges yes)
				(filter_ratio 0.9)
				(enabled yes)
				(allow_two_segments yes)
				(prefer_zone_connections yes)
			)
		)
	)
)
